FILE_TYPE = CONNECTIVITY;
{Allegro Design Entry HDL 16.6-p007 (v16-6-112F) 10/10/2012}
"PAGE_NUMBER" = 189;
0"NC";
1"P3V3_STBY\g";
2"GND\g";
3"P3V3_STBY\g";
4"P3V3_STBY\g";
5"GND\g";
6"GND\g";
7"JTAG_TMS_R";
8"PWRGD_P3V3_STBY";
9"JTAG_TRST_N";
10"JTAG_TDI";
11"FM_JTAG_PLD_EN_DEBUG";
12"JTAG_TCK";
13"P3V3_STBY_PLD_D"VOLTAGE"3.3";
14"JTAG_TCK_R";
15"JTAG_TDO_R";
16"JTAG_TDI_R";
17"JTAG_TDO";
18"JTAG_TMS";
19"JTAG_TRST_N";
20"JTAG_TDI";
21"JTAG_BMC_TRST_N";
22"JTAG_PCH_GBE_TRST_N";
23"JTAG_PCH_GBE_TDI";
24"JTAG_PCH_PLD_TDI";
25"JTAG_TMS";
26"JTAG_TCK";
27"JTAG_TDO";
28"JTAG_PCH_GBE_CLK";
29"JTAG_PLD_TMS";
30"JTAG_PLD_TDI";
31"JTAG_BMC_TMS";
32"JTAG_BMC_TDI";
33"JTAG_PCH_GBE_TMS";
34"JTAG_PCH_PLD_TCK";
35"JTAG_PCH_GBE_TDO";
36"JTAG_BMC_TCK";
37"JTAG_PLD_TCK";
38"JTAG_PCH_PLD_TDO";
39"JTAG_PCH_PLD_TMS";
40"JTAG_PLD_TDO";
41"JTAG_BMC_TDO";
%"RES"
"1","(-1900,4125)","0","mstr_discrete","I13";
;
CDS_SEC"1"
SEC_TYPE"0402"
SEC"1"
CDS_LIB"mstr_discrete"
BOM_COST"DEBUG"
ROOM"BMC_DEBUG_HEADER"
CDS_LOCATION"R7G18"
PART_NUMBER"G21497-005"
LOCATION"R7G18"
TOLERANCE"5%"
VALUE"0.0"
MATERIAL"EMPTY"
PACK_TYPE"0402"
WATTAGE"1/16W";
"B"
$PN"2"20;
"A"
$PN"1"24;
%"RES"
"1","(-1900,3950)","0","mstr_discrete","I17";
;
CDS_SEC"1"
SEC_TYPE"0402"
BOM_COST"DEBUG"
SEC"1"
CDS_LIB"mstr_discrete"
CDS_LOCATION"R8G8"
ROOM"BMC_DEBUG_HEADER"
PART_NUMBER"G21497-005"
PACK_TYPE"0402"
LOCATION"R8G8"
MATERIAL"CHIP"
TOLERANCE"5%"
WATTAGE"1/16W"
VALUE"0.0";
"B"
$PN"2"20;
"A"
$PN"1"32;
%"RES"
"1","(-1900,3775)","0","mstr_discrete","I18";
;
CDS_SEC"1"
SEC"1"
SEC_TYPE"0402"
ROOM"BMC_DEBUG_HEADER"
BOM_COST"DEBUG"
CDS_LOCATION"R8G7"
CDS_LIB"mstr_discrete"
PART_NUMBER"G21497-005"
PACK_TYPE"0402"
LOCATION"R8G7"
MATERIAL"CHIP"
TOLERANCE"5%"
WATTAGE"1/16W"
VALUE"0.0";
"B"
$PN"2"20;
"A"
$PN"1"30;
%"RES"
"1","(-1900,3400)","0","mstr_discrete","I19";
;
CDS_SEC"1"
SEC_TYPE"0402"
SEC"1"
BOM_COST"DEBUG"
CDS_LIB"mstr_discrete"
ROOM"BMC_DEBUG_HEADER"
CDS_LOCATION"R8G11"
PART_NUMBER"G21497-005"
PACK_TYPE"0402"
MATERIAL"EMPTY"
LOCATION"R8G11"
TOLERANCE"5%"
WATTAGE"1/16W"
VALUE"0.0";
"B"
$PN"2"25;
"A"
$PN"1"39;
%"RES"
"1","(-1900,3250)","0","mstr_discrete","I20";
;
CDS_SEC"1"
SEC_TYPE"0402"
SEC"1"
ROOM"BMC_DEBUG_HEADER"
BOM_COST"DEBUG"
CDS_LIB"mstr_discrete"
CDS_LOCATION"R8G14"
PART_NUMBER"G21497-005"
PACK_TYPE"0402"
LOCATION"R8G14"
MATERIAL"CHIP"
TOLERANCE"5%"
WATTAGE"1/16W"
VALUE"0.0";
"B"
$PN"2"25;
"A"
$PN"1"31;
%"RES"
"1","(-1900,3575)","0","mstr_discrete","I21";
;
CDS_SEC"1"
SEC_TYPE"0402"
SEC"1"
BOM_COST"DEBUG"
ROOM"BMC_DEBUG_HEADER"
CDS_LOCATION"R8G12"
CDS_LIB"mstr_discrete"
PART_NUMBER"G21497-005"
LOCATION"R8G12"
PACK_TYPE"0402"
MATERIAL"EMPTY"
TOLERANCE"5%"
WATTAGE"1/16W"
VALUE"0.0";
"B"
$PN"2"25;
"A"
$PN"1"33;
%"RES"
"1","(-1900,2700)","0","mstr_discrete","I22";
;
CDS_SEC"1"
BOM_COST"DEBUG"
SEC_TYPE"0402"
SEC"1"
ROOM"BMC_DEBUG_HEADER"
CDS_LIB"mstr_discrete"
CDS_LOCATION"R8G16"
PART_NUMBER"G21497-005"
PACK_TYPE"0402"
MATERIAL"EMPTY"
LOCATION"R8G16"
TOLERANCE"5%"
WATTAGE"1/16W"
VALUE"0.0";
"B"
$PN"2"26;
"A"
$PN"1"34;
%"RES"
"1","(-1900,3075)","0","mstr_discrete","I23";
;
CDS_SEC"1"
CDS_LIB"mstr_discrete"
BOM_COST"DEBUG"
SEC"1"
SEC_TYPE"0402"
ROOM"BMC_DEBUG_HEADER"
CDS_LOCATION"R8G13"
PART_NUMBER"G21497-005"
LOCATION"R8G13"
PACK_TYPE"0402"
MATERIAL"CHIP"
TOLERANCE"5%"
WATTAGE"1/16W"
VALUE"0.0";
"B"
$PN"2"25;
"A"
$PN"1"29;
%"RES"
"1","(-1900,2875)","0","mstr_discrete","I24";
;
CDS_SEC"1"
SEC"1"
SEC_TYPE"0402"
CDS_LIB"mstr_discrete"
BOM_COST"DEBUG"
ROOM"BMC_DEBUG_HEADER"
CDS_LOCATION"R8G15"
PART_NUMBER"G21497-005"
PACK_TYPE"0402"
MATERIAL"EMPTY"
LOCATION"R8G15"
TOLERANCE"5%"
WATTAGE"1/16W"
VALUE"0.0";
"B"
$PN"2"26;
"A"
$PN"1"28;
%"RES"
"1","(-1900,2525)","0","mstr_discrete","I25";
;
CDS_SEC"1"
SEC_TYPE"0402"
SEC"1"
BOM_COST"DEBUG"
CDS_LOCATION"R8G17"
ROOM"BMC_DEBUG_HEADER"
CDS_LIB"mstr_discrete"
PART_NUMBER"G21497-005"
LOCATION"R8G17"
PACK_TYPE"0402"
MATERIAL"CHIP"
TOLERANCE"5%"
WATTAGE"1/16W"
VALUE"0.0";
"B"
$PN"2"26;
"A"
$PN"1"36;
%"RES"
"1","(-1900,2350)","0","mstr_discrete","I26";
;
CDS_SEC"1"
SEC_TYPE"0402"
SEC"1"
CDS_LIB"mstr_discrete"
ROOM"BMC_DEBUG_HEADER"
BOM_COST"DEBUG"
CDS_LOCATION"R8G18"
PART_NUMBER"G21497-005"
PACK_TYPE"0402"
LOCATION"R8G18"
MATERIAL"CHIP"
TOLERANCE"5%"
WATTAGE"1/16W"
VALUE"0.0";
"B"
$PN"2"26;
"A"
$PN"1"37;
%"RES"
"1","(-1900,2150)","0","mstr_discrete","I27";
;
CDS_SEC"1"
SEC"1"
SEC_TYPE"0402"
BOM_COST"DEBUG"
CDS_LIB"mstr_discrete"
CDS_LOCATION"R7G16"
ROOM"BMC_DEBUG_HEADER"
PART_NUMBER"G21497-005"
PACK_TYPE"0402"
MATERIAL"EMPTY"
LOCATION"R7G16"
TOLERANCE"5%"
WATTAGE"1/16W"
VALUE"0.0";
"B"
$PN"2"27;
"A"
$PN"1"35;
%"RES"
"1","(-1900,1975)","0","mstr_discrete","I36";
;
CDS_SEC"1"
SEC_TYPE"0402"
SEC"1"
BOM_COST"DEBUG"
ROOM"BMC_DEBUG_HEADER"
CDS_LOCATION"R7G15"
CDS_LIB"mstr_discrete"
LOCATION"R7G15"
PART_NUMBER"G21497-005"
PACK_TYPE"0402"
MATERIAL"EMPTY"
TOLERANCE"5%"
WATTAGE"1/16W"
VALUE"0.0";
"B"
$PN"2"27;
"A"
$PN"1"38;
%"RES"
"1","(-1900,1800)","0","mstr_discrete","I37";
;
CDS_SEC"1"
CDS_LIB"mstr_discrete"
SEC_TYPE"0402"
BOM_COST"DEBUG"
SEC"1"
ROOM"BMC_DEBUG_HEADER"
CDS_LOCATION"R7G17"
PART_NUMBER"G21497-005"
PACK_TYPE"0402"
LOCATION"R7G17"
MATERIAL"CHIP"
TOLERANCE"5%"
WATTAGE"1/16W"
VALUE"0.0";
"B"
$PN"2"27;
"A"
$PN"1"41;
%"RES"
"1","(-1900,1625)","0","mstr_discrete","I38";
;
CDS_SEC"1"
SEC_TYPE"0402"
SEC"1"
BOM_COST"DEBUG"
CDS_LIB"mstr_discrete"
ROOM"BMC_DEBUG_HEADER"
CDS_LOCATION"R7G14"
PART_NUMBER"G21497-005"
PACK_TYPE"0402"
LOCATION"R7G14"
MATERIAL"CHIP"
TOLERANCE"5%"
WATTAGE"1/16W"
VALUE"0.0";
"B"
$PN"2"27;
"A"
$PN"1"40;
%"P3V3_STBY"
"1","(-175,2125)","0","mstr_symbols","I43";
;
BODY_TYPE"PLUMBING"
SIZE"1B"
CDS_LIB"mstr_symbols"
VOLTAGE"3.3V"
HDL_POWER"P3V3_STBY";
"G\NAC"1;
%"RES"
"2","(-175,1925)","0","mstr_discrete","I44";
;
CDS_SEC"1"
SEC_TYPE"0402"
SEC"1"
CDS_LOCATION"R3R15"
ROOM"BMC_DEBUG_HEADER"
CDS_LIB"mstr_discrete"
LOCATION"R3R15"
PART_NUMBER"G21796-026"
VALUE"1.00K"
WATTAGE"1/16W"
MATERIAL"CHIP"
TOLERANCE"1%"
PACK_TYPE"0402";
"A"
$PN"1"1;
"B"
$PN"2"11;
%"RES"
"2","(-175,1525)","0","mstr_discrete","I45";
;
CDS_SEC"1"
SEC_TYPE"0402"
ROOM"BMC_DEBUG_HEADER"
SEC"1"
CDS_LOCATION"R3R11"
CDS_LIB"mstr_discrete"
VALUE"10.0K"
TOLERANCE"1%"
WATTAGE"1/16W"
MATERIAL"EMPTY"
LOCATION"R3R11"
PART_NUMBER"G21796-016"
PACK_TYPE"0402";
"A"
$PN"1"11;
"B"
$PN"2"2;
%"GND"
"1","(-175,1325)","0","mstr_symbols","I46";
;
HDL_POWER"GND"
VOLTAGE"0.0V"
CDS_LIB"mstr_symbols"
BODY_TYPE"PLUMBING"
SIZE"1B";
"A\NAC"2;
%"CONN8_C77962004"
"1","(3475,3625)","2","mstr_conn","I47";
;
CDS_SEC"1"
BOM_COST"DEBUG"
SEC_TYPE"PIP"
SEC"1"
ROOM"BMC_DEBUG_HEADER"
PACK_TYPE"PIP"
CDS_LIB"mstr_conn"
CDS_LOCATION"J7G2"
PART_NUMBER"C77962-004"
MATERIAL"CONN"
LOCATION"J7G2";
"IO1"
$PN"1"13;
"IO2"
$PN"2"15;
"IO3"
$PN"3"16;
"IO4"
$PN"4"9;
"IO5"
$PN"5"8;
"IO6"
$PN"6"7;
"IO7"
$PN"7"5;
"IO8"
$PN"8"14;
%"P3V3_STBY"
"1","(2650,4350)","0","mstr_symbols","I48";
;
SIZE"1B"
CDS_LIB"mstr_symbols"
VOLTAGE"3.3V"
BODY_TYPE"PLUMBING"
HDL_POWER"P3V3_STBY";
"G\NAC"3;
%"DIODE"
"1","(2800,4050)","0","mstr_discrete","I49";
;
CDS_SEC"1"
CDS_LOCATION"CR3U1"
BOM_COST"DEBUG"
SEC"1"
SEC_TYPE"SMLF"
ROOM"BMC_DEBUG_HEADER"
CDS_LIB"mstr_discrete"
LOCATION"CR3U1"
VALUE"1N5819HW"
PACK_TYPE"SMLF"
PART_NUMBER"D55839-001"
MATERIAL"IC";
"C"
$PN"1"13;
"A"
$PN"2"3;
%"RES"
"2","(2325,3975)","0","mstr_discrete","I50";
;
CDS_SEC"1"
$SEC"1"
CDS_LOCATION"R8G20"
ROOM"BMC_DEBUG_HEADER"
CDS_LIB"mstr_discrete"
LOCATION"R8G20"
PART_NUMBER"G21796-016"
VALUE"10.0K"
MATERIAL"CHIP"
WATTAGE"1/16W"
TOLERANCE"1%"
PACK_TYPE"0402";
"A"
$PN"1"4;
"B"
$PN"2"7;
%"RES"
"2","(2025,3975)","0","mstr_discrete","I51";
;
$SEC"1"
CDS_LOCATION"R7G23"
CDS_SEC"1"
ROOM"BMC_DEBUG_HEADER"
CDS_LIB"mstr_discrete"
LOCATION"R7G23"
PART_NUMBER"G21796-016"
MATERIAL"CHIP"
TOLERANCE"1%"
WATTAGE"1/16W"
PACK_TYPE"0402"
VALUE"10.0K";
"A"
$PN"1"4;
"B"
$PN"2"16;
%"P3V3_STBY"
"1","(1675,4300)","0","mstr_symbols","I52";
;
SIZE"1B"
CDS_LIB"mstr_symbols"
BODY_TYPE"PLUMBING"
VOLTAGE"3.3V"
HDL_POWER"P3V3_STBY";
"G\NAC"4;
%"RES"
"2","(1675,3975)","0","mstr_discrete","I53";
;
$SEC"1"
CDS_SEC"1"
CDS_LOCATION"R7G22"
ROOM"BMC_DEBUG_HEADER"
CDS_LIB"mstr_discrete"
LOCATION"R7G22"
PART_NUMBER"G21796-016"
VALUE"10.0K"
PACK_TYPE"0402"
MATERIAL"CHIP"
WATTAGE"1/16W"
TOLERANCE"1%";
"A"
$PN"1"4;
"B"
$PN"2"15;
%"GND"
"1","(3150,3300)","0","mstr_symbols","I54";
;
HDL_POWER"GND"
CDS_LIB"mstr_symbols"
VOLTAGE"0.0V"
SIZE"1B"
BODY_TYPE"PLUMBING";
"A\NAC"5;
%"GND"
"1","(2325,2925)","0","mstr_symbols","I55";
;
HDL_POWER"GND"
VOLTAGE"0.0V"
CDS_LIB"mstr_symbols"
SIZE"1B"
BODY_TYPE"PLUMBING";
"A\NAC"6;
%"RES"
"2","(2325,3225)","0","mstr_discrete","I56";
;
CDS_SEC"1"
SEC_TYPE"0402"
SEC"1"
CDS_LOCATION"R8G23"
CDS_LIB"mstr_discrete"
ROOM"BMC_DEBUG_HEADER"
PACK_TYPE"0402"
PART_NUMBER"G21796-072"
LOCATION"R8G23"
MATERIAL"CHIP"
WATTAGE"1/16W"
VALUE"4.75K"
TOLERANCE"1%";
"A"
$PN"1"14;
"B"
$PN"2"6;
%"RES"
"1","(900,3725)","0","mstr_discrete","I63";
;
CDS_SEC"1"
BOM_COST"DEBUG"
SEC_TYPE"0402"
SEC"1"
ROOM"BMC_DEBUG_HEADER"
CDS_LIB"mstr_discrete"
CDS_LOCATION"R7G21"
PART_NUMBER"G21497-005"
PACK_TYPE"0402"
LOCATION"R7G21"
MATERIAL"CHIP"
TOLERANCE"5%"
WATTAGE"1/16W"
VALUE"0.0";
"B"
$PN"2"15;
"A"
$PN"1"17;
%"RES"
"1","(1375,3675)","0","mstr_discrete","I64";
;
CDS_SEC"1"
SEC_TYPE"0402"
SEC"1"
BOM_COST"DEBUG"
ROOM"BMC_DEBUG_HEADER"
CDS_LOCATION"R8G19"
CDS_LIB"mstr_discrete"
PART_NUMBER"G21497-005"
PACK_TYPE"0402"
LOCATION"R8G19"
MATERIAL"CHIP"
TOLERANCE"5%"
WATTAGE"1/16W"
VALUE"0.0";
"B"
$PN"2"16;
"A"
$PN"1"10;
%"RES"
"1","(975,3525)","0","mstr_discrete","I65";
;
CDS_SEC"1"
ROOM"BMC_DEBUG_HEADER"
SEC"1"
SEC_TYPE"0402"
BOM_COST"DEBUG"
CDS_LOCATION"R8G21"
CDS_LIB"mstr_discrete"
PART_NUMBER"G21497-005"
PACK_TYPE"0402"
LOCATION"R8G21"
MATERIAL"CHIP"
TOLERANCE"5%"
WATTAGE"1/16W"
VALUE"0.0";
"B"
$PN"2"7;
"A"
$PN"1"18;
%"RES"
"1","(1600,3425)","0","mstr_discrete","I66";
;
CDS_SEC"1"
SEC"1"
SEC_TYPE"0402"
BOM_COST"DEBUG"
ROOM"BMC_DEBUG_HEADER"
CDS_LOCATION"R8G22"
CDS_LIB"mstr_discrete"
PACK_TYPE"0402"
LOCATION"R8G22"
PART_NUMBER"G21497-005"
MATERIAL"CHIP"
WATTAGE"1/16W"
TOLERANCE"5%"
VALUE"0.0";
"B"
$PN"2"14;
"A"
$PN"1"12;
%"RES"
"1","(-1900,4675)","0","mstr_discrete","I7";
;
CDS_SEC"1"
SEC_TYPE"0402"
SEC"1"
BOM_COST"DEBUG"
CDS_LIB"mstr_discrete"
CDS_LOCATION"R8G10"
ROOM"BMC_DEBUG_HEADER"
PART_NUMBER"G21497-005"
PACK_TYPE"0402"
LOCATION"R8G10"
MATERIAL"CHIP"
TOLERANCE"5%"
WATTAGE"1/16W"
VALUE"0.0";
"B"
$PN"2"19;
"A"
$PN"1"21;
%"RES"
"1","(-1900,4300)","0","mstr_discrete","I8";
;
CDS_SEC"1"
SEC_TYPE"0402"
SEC"1"
BOM_COST"DEBUG"
ROOM"BMC_DEBUG_HEADER"
CDS_LOCATION"R7G19"
CDS_LIB"mstr_discrete"
PART_NUMBER"G21497-005"
PACK_TYPE"0402"
LOCATION"R7G19"
MATERIAL"EMPTY"
TOLERANCE"5%"
WATTAGE"1/16W"
VALUE"0.0";
"B"
$PN"2"20;
"A"
$PN"1"23;
%"RES"
"1","(-1900,4500)","0","mstr_discrete","I9";
;
$SEC"1"
CDS_SEC"1"
BOM_COST"DEBUG"
ROOM"BMC_DEBUG_HEADER"
CDS_LIB"mstr_discrete"
CDS_LOCATION"R8G9"
PART_NUMBER"G21497-005"
PACK_TYPE"0402"
MATERIAL"EMPTY"
LOCATION"R8G9"
TOLERANCE"5%"
WATTAGE"1/16W"
VALUE"0.0";
"B"
$PN"2"19;
"A"
$PN"1"22;
END.
